(kicad_pcb
	(version 20260206)
	(generator "pcbnew")
	(generator_version "10.0")
	(general
		(thickness 1.6)
		(legacy_teardrops no)
	)
	(paper "A4")
	(title_block
		(title "01162023_DA0F0TEBIF0_F0T_Expander_BD_F_brd_V02_OCP.brd")
		(comment 1 "Grand Teton / footprints 967-973 of 9728")
	)
	(layers
		(0 "F.Cu" signal "TOP")
		(4 "In1.Cu" signal "GND")
		(6 "In2.Cu" signal "VCC")
		(8 "In3.Cu" signal "VCC1")
		(10 "In4.Cu" signal "GND1")
		(12 "In5.Cu" signal "IN1")
		(14 "In6.Cu" signal "GND2")
		(16 "In7.Cu" signal "IN2")
		(18 "In8.Cu" signal "GND3")
		(20 "In9.Cu" signal "IN3")
		(22 "In10.Cu" signal "GND4")
		(24 "In11.Cu" signal "IN4")
		(26 "In12.Cu" signal "GND5")
		(28 "In13.Cu" signal "IN5")
		(30 "In14.Cu" signal "GND6")
		(32 "In15.Cu" signal "IN6")
		(34 "In16.Cu" signal "GND7")
		(2 "B.Cu" signal "BOTTOM")
		(9 "F.Adhes" user "F.Adhesive")
		(11 "B.Adhes" user "B.Adhesive")
		(13 "F.Paste" user "Package Geometry/Pastemask Top")
		(15 "B.Paste" user "Package Geometry/Pastemask Bottom")
		(5 "F.SilkS" user "Ref Des/Silkscreen Top")
		(7 "B.SilkS" user "Ref Des/Silkscreen Bottom")
		(1 "F.Mask" user "Board Geometry/Soldermask Top")
		(3 "B.Mask" user "Board Geometry/Soldermask Bottom")
		(17 "Dwgs.User" user "User.Drawings")
		(19 "Cmts.User" user "User.Comments")
		(21 "Eco1.User" user "User.Eco1")
		(23 "Eco2.User" user "User.Eco2")
		(25 "Edge.Cuts" user "Board Geometry/Outline")
		(27 "Margin" user)
		(31 "F.CrtYd" user "Package Geometry/Place Bound Top")
		(29 "B.CrtYd" user "Package Geometry/Place Bound Bottom")
		(35 "F.Fab" user "Ref Des/Assembly Top")
		(33 "B.Fab" user "Ref Des/Assembly Bottom")
	)
	(footprint ""
		(layer "F.Cu")
		(at 259.951474 -260.840982)
		(property "Reference" "R4587"
			(at 0 0 0)
			(layer "F.SilkS")
			(hide yes)
			(effects
				(font
					(size 1.27 1.27)
				)
			)
		)
		(property "Value" ""
			(at 0 0 0)
			(layer "F.Fab")
			(effects
				(font
					(size 1.27 1.27)
				)
			)
		)
		(duplicate_pad_numbers_are_jumpers no)
		(fp_line
			(start -0.7874 -0.4064)
			(end 0.7874 -0.4064)
			(stroke
				(width 0.1524)
				(type default)
			)
			(layer "F.SilkS")
		)
		(fp_line
			(start -0.7874 0.4064)
			(end -0.7874 -0.4064)
			(stroke
				(width 0.1524)
				(type default)
			)
			(layer "F.SilkS")
		)
		(fp_line
			(start 0.7874 -0.4064)
			(end 0.7874 0.4064)
			(stroke
				(width 0.1524)
				(type default)
			)
			(layer "F.SilkS")
		)
		(fp_line
			(start 0.7874 0.4064)
			(end -0.7874 0.4064)
			(stroke
				(width 0.1524)
				(type default)
			)
			(layer "F.SilkS")
		)
		(fp_line
			(start -0.67945 -0.305054)
			(end -0.12065 -0.305054)
			(stroke
				(width 0.1)
				(type default)
			)
			(layer "F.Fab")
		)
		(fp_line
			(start -0.67945 0.3048)
			(end -0.67945 -0.305054)
			(stroke
				(width 0.1)
				(type default)
			)
			(layer "F.Fab")
		)
		(fp_line
			(start -0.12065 -0.305054)
			(end -0.12065 -0.2794)
			(stroke
				(width 0.1)
				(type default)
			)
			(layer "F.Fab")
		)
		(fp_line
			(start -0.12065 -0.2794)
			(end 0.12065 -0.2794)
			(stroke
				(width 0.1)
				(type default)
			)
			(layer "F.Fab")
		)
		(fp_line
			(start -0.12065 0.2794)
			(end -0.12065 0.3048)
			(stroke
				(width 0.1)
				(type default)
			)
			(layer "F.Fab")
		)
		(fp_line
			(start -0.12065 0.3048)
			(end -0.67945 0.3048)
			(stroke
				(width 0.1)
				(type default)
			)
			(layer "F.Fab")
		)
		(fp_line
			(start 0.120396 0.2794)
			(end -0.12065 0.2794)
			(stroke
				(width 0.1)
				(type default)
			)
			(layer "F.Fab")
		)
		(fp_line
			(start 0.120396 0.3048)
			(end 0.120396 0.2794)
			(stroke
				(width 0.1)
				(type default)
			)
			(layer "F.Fab")
		)
		(fp_line
			(start 0.12065 -0.3048)
			(end 0.67945 -0.3048)
			(stroke
				(width 0.1)
				(type default)
			)
			(layer "F.Fab")
		)
		(fp_line
			(start 0.12065 -0.2794)
			(end 0.12065 -0.3048)
			(stroke
				(width 0.1)
				(type default)
			)
			(layer "F.Fab")
		)
		(fp_line
			(start 0.67945 -0.3048)
			(end 0.67945 0.3048)
			(stroke
				(width 0.1)
				(type default)
			)
			(layer "F.Fab")
		)
		(fp_line
			(start 0.67945 0.3048)
			(end 0.120396 0.3048)
			(stroke
				(width 0.1)
				(type default)
			)
			(layer "F.Fab")
		)
		(pad "1" smd circle
			(at -0.40005 0)
			(size 0 0)
			(layers "F.Cu" "F.Mask" "F.Paste")
			(net "P1V8_VDDA_PEX2")
		)
		(pad "2" smd circle
			(at 0.40005 0)
			(size 0 0)
			(layers "F.Cu" "F.Mask" "F.Paste")
			(net "P1V8_VDDA_PEX2_R")
		)
	)
	(footprint ""
		(layer "F.Cu")
		(at 426.567854 -53.051456)
		(property "Reference" "R4471"
			(at 0 0 0)
			(layer "F.SilkS")
			(hide yes)
			(effects
				(font
					(size 1.27 1.27)
				)
			)
		)
		(property "Value" ""
			(at 0 0 0)
			(layer "F.Fab")
			(effects
				(font
					(size 1.27 1.27)
				)
			)
		)
		(duplicate_pad_numbers_are_jumpers no)
		(fp_line
			(start -0.7874 -0.4064)
			(end 0.7874 -0.4064)
			(stroke
				(width 0.1524)
				(type default)
			)
			(layer "F.SilkS")
		)
		(fp_line
			(start -0.7874 0.4064)
			(end -0.7874 -0.4064)
			(stroke
				(width 0.1524)
				(type default)
			)
			(layer "F.SilkS")
		)
		(fp_line
			(start 0.7874 -0.4064)
			(end 0.7874 0.4064)
			(stroke
				(width 0.1524)
				(type default)
			)
			(layer "F.SilkS")
		)
		(fp_line
			(start 0.7874 0.4064)
			(end -0.7874 0.4064)
			(stroke
				(width 0.1524)
				(type default)
			)
			(layer "F.SilkS")
		)
		(fp_line
			(start -0.67945 -0.305054)
			(end -0.12065 -0.305054)
			(stroke
				(width 0.1)
				(type default)
			)
			(layer "F.Fab")
		)
		(fp_line
			(start -0.67945 0.3048)
			(end -0.67945 -0.305054)
			(stroke
				(width 0.1)
				(type default)
			)
			(layer "F.Fab")
		)
		(fp_line
			(start -0.12065 -0.305054)
			(end -0.12065 -0.2794)
			(stroke
				(width 0.1)
				(type default)
			)
			(layer "F.Fab")
		)
		(fp_line
			(start -0.12065 -0.2794)
			(end 0.12065 -0.2794)
			(stroke
				(width 0.1)
				(type default)
			)
			(layer "F.Fab")
		)
		(fp_line
			(start -0.12065 0.2794)
			(end -0.12065 0.3048)
			(stroke
				(width 0.1)
				(type default)
			)
			(layer "F.Fab")
		)
		(fp_line
			(start -0.12065 0.3048)
			(end -0.67945 0.3048)
			(stroke
				(width 0.1)
				(type default)
			)
			(layer "F.Fab")
		)
		(fp_line
			(start 0.120396 0.2794)
			(end -0.12065 0.2794)
			(stroke
				(width 0.1)
				(type default)
			)
			(layer "F.Fab")
		)
		(fp_line
			(start 0.120396 0.3048)
			(end 0.120396 0.2794)
			(stroke
				(width 0.1)
				(type default)
			)
			(layer "F.Fab")
		)
		(fp_line
			(start 0.12065 -0.3048)
			(end 0.67945 -0.3048)
			(stroke
				(width 0.1)
				(type default)
			)
			(layer "F.Fab")
		)
		(fp_line
			(start 0.12065 -0.2794)
			(end 0.12065 -0.3048)
			(stroke
				(width 0.1)
				(type default)
			)
			(layer "F.Fab")
		)
		(fp_line
			(start 0.67945 -0.3048)
			(end 0.67945 0.3048)
			(stroke
				(width 0.1)
				(type default)
			)
			(layer "F.Fab")
		)
		(fp_line
			(start 0.67945 0.3048)
			(end 0.120396 0.3048)
			(stroke
				(width 0.1)
				(type default)
			)
			(layer "F.Fab")
		)
		(pad "1" smd circle
			(at -0.40005 0)
			(size 0 0)
			(layers "F.Cu" "F.Mask" "F.Paste")
			(net "PWRGD_P12V_SSD14")
		)
		(pad "2" smd circle
			(at 0.40005 0)
			(size 0 0)
			(layers "F.Cu" "F.Mask" "F.Paste")
			(net "PWRGD_P12V_SSD14_R")
		)
	)
	(footprint ""
		(layer "F.Cu")
		(at 162.5346 -33.631886 180)
		(property "Reference" "C285"
			(at 0 0 180)
			(layer "F.SilkS")
			(hide yes)
			(effects
				(font
					(size 1.27 1.27)
				)
			)
		)
		(property "Value" ""
			(at 0 0 180)
			(layer "F.Fab")
			(effects
				(font
					(size 1.27 1.27)
				)
			)
		)
		(duplicate_pad_numbers_are_jumpers no)
		(fp_line
			(start 0.299974 0.150114)
			(end -0.299974 0.150114)
			(stroke
				(width 0.1)
				(type default)
			)
			(layer "F.Fab")
		)
		(fp_line
			(start 0.299974 -0.150114)
			(end 0.299974 0.150114)
			(stroke
				(width 0.1)
				(type default)
			)
			(layer "F.Fab")
		)
		(fp_line
			(start -0.299974 0.150114)
			(end -0.299974 -0.150114)
			(stroke
				(width 0.1)
				(type default)
			)
			(layer "F.Fab")
		)
		(fp_line
			(start -0.299974 -0.150114)
			(end 0.299974 -0.150114)
			(stroke
				(width 0.1)
				(type default)
			)
			(layer "F.Fab")
		)
		(pad "1" smd rect
			(at -0.2667 0 180)
			(size 0.3048 0.381)
			(layers "F.Cu" "F.Mask" "F.Paste")
			(net "P5E_PEX1_STN2_TX_DN<43>")
		)
		(pad "2" smd rect
			(at 0.2667 0 180)
			(size 0.3048 0.381)
			(layers "F.Cu" "F.Mask" "F.Paste")
			(net "P5E_PEX1_STN2_TX_C_DN<43>")
		)
	)
	(footprint ""
		(layer "F.Cu")
		(at 258.44373 -44.87291)
		(property "Reference" "R595"
			(at 0 0 0)
			(layer "F.SilkS")
			(hide yes)
			(effects
				(font
					(size 1.27 1.27)
				)
			)
		)
		(property "Value" ""
			(at 0 0 0)
			(layer "F.Fab")
			(effects
				(font
					(size 1.27 1.27)
				)
			)
		)
		(duplicate_pad_numbers_are_jumpers no)
		(fp_line
			(start -0.7874 -0.4064)
			(end 0.7874 -0.4064)
			(stroke
				(width 0.1524)
				(type default)
			)
			(layer "F.SilkS")
		)
		(fp_line
			(start -0.7874 0.4064)
			(end -0.7874 -0.4064)
			(stroke
				(width 0.1524)
				(type default)
			)
			(layer "F.SilkS")
		)
		(fp_line
			(start 0.7874 -0.4064)
			(end 0.7874 0.4064)
			(stroke
				(width 0.1524)
				(type default)
			)
			(layer "F.SilkS")
		)
		(fp_line
			(start 0.7874 0.4064)
			(end -0.7874 0.4064)
			(stroke
				(width 0.1524)
				(type default)
			)
			(layer "F.SilkS")
		)
		(fp_line
			(start -0.67945 -0.305054)
			(end -0.12065 -0.305054)
			(stroke
				(width 0.1)
				(type default)
			)
			(layer "F.Fab")
		)
		(fp_line
			(start -0.67945 0.3048)
			(end -0.67945 -0.305054)
			(stroke
				(width 0.1)
				(type default)
			)
			(layer "F.Fab")
		)
		(fp_line
			(start -0.12065 -0.305054)
			(end -0.12065 -0.2794)
			(stroke
				(width 0.1)
				(type default)
			)
			(layer "F.Fab")
		)
		(fp_line
			(start -0.12065 -0.2794)
			(end 0.12065 -0.2794)
			(stroke
				(width 0.1)
				(type default)
			)
			(layer "F.Fab")
		)
		(fp_line
			(start -0.12065 0.2794)
			(end -0.12065 0.3048)
			(stroke
				(width 0.1)
				(type default)
			)
			(layer "F.Fab")
		)
		(fp_line
			(start -0.12065 0.3048)
			(end -0.67945 0.3048)
			(stroke
				(width 0.1)
				(type default)
			)
			(layer "F.Fab")
		)
		(fp_line
			(start 0.120396 0.2794)
			(end -0.12065 0.2794)
			(stroke
				(width 0.1)
				(type default)
			)
			(layer "F.Fab")
		)
		(fp_line
			(start 0.120396 0.3048)
			(end 0.120396 0.2794)
			(stroke
				(width 0.1)
				(type default)
			)
			(layer "F.Fab")
		)
		(fp_line
			(start 0.12065 -0.3048)
			(end 0.67945 -0.3048)
			(stroke
				(width 0.1)
				(type default)
			)
			(layer "F.Fab")
		)
		(fp_line
			(start 0.12065 -0.2794)
			(end 0.12065 -0.3048)
			(stroke
				(width 0.1)
				(type default)
			)
			(layer "F.Fab")
		)
		(fp_line
			(start 0.67945 -0.3048)
			(end 0.67945 0.3048)
			(stroke
				(width 0.1)
				(type default)
			)
			(layer "F.Fab")
		)
		(fp_line
			(start 0.67945 0.3048)
			(end 0.120396 0.3048)
			(stroke
				(width 0.1)
				(type default)
			)
			(layer "F.Fab")
		)
		(pad "1" smd circle
			(at -0.40005 0)
			(size 0 0)
			(layers "F.Cu" "F.Mask" "F.Paste")
			(net "SSD8_ADC_A0")
		)
		(pad "2" smd circle
			(at 0.40005 0)
			(size 0 0)
			(layers "F.Cu" "F.Mask" "F.Paste")
			(net "P3V3_AUX")
		)
	)
	(footprint ""
		(layer "F.Cu")
		(at 211.511388 -369.44935)
		(property "Reference" "PR11"
			(at 0 0 0)
			(layer "F.SilkS")
			(hide yes)
			(effects
				(font
					(size 1.27 1.27)
				)
			)
		)
		(property "Value" ""
			(at 0 0 0)
			(layer "F.Fab")
			(effects
				(font
					(size 1.27 1.27)
				)
			)
		)
		(duplicate_pad_numbers_are_jumpers no)
		(fp_line
			(start -0.7874 -0.4064)
			(end 0.7874 -0.4064)
			(stroke
				(width 0.1524)
				(type default)
			)
			(layer "F.SilkS")
		)
		(fp_line
			(start -0.7874 0.4064)
			(end -0.7874 -0.4064)
			(stroke
				(width 0.1524)
				(type default)
			)
			(layer "F.SilkS")
		)
		(fp_line
			(start 0.7874 -0.4064)
			(end 0.7874 0.4064)
			(stroke
				(width 0.1524)
				(type default)
			)
			(layer "F.SilkS")
		)
		(fp_line
			(start 0.7874 0.4064)
			(end -0.7874 0.4064)
			(stroke
				(width 0.1524)
				(type default)
			)
			(layer "F.SilkS")
		)
		(fp_line
			(start -0.67945 -0.305054)
			(end -0.12065 -0.305054)
			(stroke
				(width 0.1)
				(type default)
			)
			(layer "F.Fab")
		)
		(fp_line
			(start -0.67945 0.3048)
			(end -0.67945 -0.305054)
			(stroke
				(width 0.1)
				(type default)
			)
			(layer "F.Fab")
		)
		(fp_line
			(start -0.12065 -0.305054)
			(end -0.12065 -0.2794)
			(stroke
				(width 0.1)
				(type default)
			)
			(layer "F.Fab")
		)
		(fp_line
			(start -0.12065 -0.2794)
			(end 0.12065 -0.2794)
			(stroke
				(width 0.1)
				(type default)
			)
			(layer "F.Fab")
		)
		(fp_line
			(start -0.12065 0.2794)
			(end -0.12065 0.3048)
			(stroke
				(width 0.1)
				(type default)
			)
			(layer "F.Fab")
		)
		(fp_line
			(start -0.12065 0.3048)
			(end -0.67945 0.3048)
			(stroke
				(width 0.1)
				(type default)
			)
			(layer "F.Fab")
		)
		(fp_line
			(start 0.120396 0.2794)
			(end -0.12065 0.2794)
			(stroke
				(width 0.1)
				(type default)
			)
			(layer "F.Fab")
		)
		(fp_line
			(start 0.120396 0.3048)
			(end 0.120396 0.2794)
			(stroke
				(width 0.1)
				(type default)
			)
			(layer "F.Fab")
		)
		(fp_line
			(start 0.12065 -0.3048)
			(end 0.67945 -0.3048)
			(stroke
				(width 0.1)
				(type default)
			)
			(layer "F.Fab")
		)
		(fp_line
			(start 0.12065 -0.2794)
			(end 0.12065 -0.3048)
			(stroke
				(width 0.1)
				(type default)
			)
			(layer "F.Fab")
		)
		(fp_line
			(start 0.67945 -0.3048)
			(end 0.67945 0.3048)
			(stroke
				(width 0.1)
				(type default)
			)
			(layer "F.Fab")
		)
		(fp_line
			(start 0.67945 0.3048)
			(end 0.120396 0.3048)
			(stroke
				(width 0.1)
				(type default)
			)
			(layer "F.Fab")
		)
		(pad "1" smd circle
			(at -0.40005 0)
			(size 0 0)
			(layers "F.Cu" "F.Mask" "F.Paste")
			(net "HSC_MODE")
		)
		(pad "2" smd circle
			(at 0.40005 0)
			(size 0 0)
			(layers "F.Cu" "F.Mask" "F.Paste")
			(net "AGND_HSC")
		)
	)
	(footprint ""
		(layer "F.Cu")
		(at 142.684246 -29.222954 -90)
		(property "Reference" "PC919"
			(at 0 0 270)
			(layer "F.SilkS")
			(hide yes)
			(effects
				(font
					(size 1.27 1.27)
				)
			)
		)
		(property "Value" ""
			(at 0 0 270)
			(layer "F.Fab")
			(effects
				(font
					(size 1.27 1.27)
				)
			)
		)
		(duplicate_pad_numbers_are_jumpers no)
		(fp_line
			(start -0.7874 0.4064)
			(end -0.7874 -0.4064)
			(stroke
				(width 0.1524)
				(type default)
			)
			(layer "F.SilkS")
		)
		(fp_line
			(start 0.7874 0.4064)
			(end -0.7874 0.4064)
			(stroke
				(width 0.1524)
				(type default)
			)
			(layer "F.SilkS")
		)
		(fp_line
			(start -0.7874 -0.4064)
			(end 0.7874 -0.4064)
			(stroke
				(width 0.1524)
				(type default)
			)
			(layer "F.SilkS")
		)
		(fp_line
			(start 0.7874 -0.4064)
			(end 0.7874 0.4064)
			(stroke
				(width 0.1524)
				(type default)
			)
			(layer "F.SilkS")
		)
		(fp_line
			(start -0.67945 0.3048)
			(end -0.67945 -0.305054)
			(stroke
				(width 0.1)
				(type default)
			)
			(layer "F.Fab")
		)
		(fp_line
			(start -0.12065 0.3048)
			(end -0.67945 0.3048)
			(stroke
				(width 0.1)
				(type default)
			)
			(layer "F.Fab")
		)
		(fp_line
			(start 0.120396 0.3048)
			(end 0.120396 0.2794)
			(stroke
				(width 0.1)
				(type default)
			)
			(layer "F.Fab")
		)
		(fp_line
			(start 0.67945 0.3048)
			(end 0.120396 0.3048)
			(stroke
				(width 0.1)
				(type default)
			)
			(layer "F.Fab")
		)
		(fp_line
			(start -0.12065 0.2794)
			(end -0.12065 0.3048)
			(stroke
				(width 0.1)
				(type default)
			)
			(layer "F.Fab")
		)
		(fp_line
			(start 0.120396 0.2794)
			(end -0.12065 0.2794)
			(stroke
				(width 0.1)
				(type default)
			)
			(layer "F.Fab")
		)
		(fp_line
			(start -0.12065 -0.2794)
			(end 0.12065 -0.2794)
			(stroke
				(width 0.1)
				(type default)
			)
			(layer "F.Fab")
		)
		(fp_line
			(start 0.12065 -0.2794)
			(end 0.12065 -0.3048)
			(stroke
				(width 0.1)
				(type default)
			)
			(layer "F.Fab")
		)
		(fp_line
			(start 0.12065 -0.3048)
			(end 0.67945 -0.3048)
			(stroke
				(width 0.1)
				(type default)
			)
			(layer "F.Fab")
		)
		(fp_line
			(start 0.67945 -0.3048)
			(end 0.67945 0.3048)
			(stroke
				(width 0.1)
				(type default)
			)
			(layer "F.Fab")
		)
		(fp_line
			(start -0.67945 -0.305054)
			(end -0.12065 -0.305054)
			(stroke
				(width 0.1)
				(type default)
			)
			(layer "F.Fab")
		)
		(fp_line
			(start -0.12065 -0.305054)
			(end -0.12065 -0.2794)
			(stroke
				(width 0.1)
				(type default)
			)
			(layer "F.Fab")
		)
		(pad "1" smd circle
			(at -0.40005 0 270)
			(size 0 0)
			(layers "F.Cu" "F.Mask" "F.Paste")
			(net "P3V3_AUX")
		)
		(pad "2" smd circle
			(at 0.40005 0 270)
			(size 0 0)
			(layers "F.Cu" "F.Mask" "F.Paste")
			(net "GND")
		)
	)
	(footprint ""
		(layer "F.Cu")
		(at 177.705512 -350.098614 90)
		(property "Reference" "C386"
			(at 0 0 90)
			(layer "F.SilkS")
			(hide yes)
			(effects
				(font
					(size 1.27 1.27)
				)
			)
		)
		(property "Value" ""
			(at 0 0 90)
			(layer "F.Fab")
			(effects
				(font
					(size 1.27 1.27)
				)
			)
		)
		(duplicate_pad_numbers_are_jumpers no)
		(fp_line
			(start 0.299974 -0.150114)
			(end 0.299974 0.150114)
			(stroke
				(width 0.1)
				(type default)
			)
			(layer "F.Fab")
		)
		(fp_line
			(start -0.299974 -0.150114)
			(end 0.299974 -0.150114)
			(stroke
				(width 0.1)
				(type default)
			)
			(layer "F.Fab")
		)
		(fp_line
			(start 0.299974 0.150114)
			(end -0.299974 0.150114)
			(stroke
				(width 0.1)
				(type default)
			)
			(layer "F.Fab")
		)
		(fp_line
			(start -0.299974 0.150114)
			(end -0.299974 -0.150114)
			(stroke
				(width 0.1)
				(type default)
			)
			(layer "F.Fab")
		)
		(pad "1" smd rect
			(at -0.2667 0 90)
			(size 0.3048 0.381)
			(layers "F.Cu" "F.Mask" "F.Paste")
			(net "P5E_PEX1_STN7_TX_DP<120>")
		)
		(pad "2" smd rect
			(at 0.2667 0 90)
			(size 0.3048 0.381)
			(layers "F.Cu" "F.Mask" "F.Paste")
			(net "P5E_PEX1_STN7_TX_C_DP<120>")
		)
	)
)
